FILE_TYPE=LIBRARY_PARTS;
primitive 'Q_XTAL_4P_13BI_24GND';
  pin
    'X1':
      PIN_NUMBER='(1)';
      BIDIRECTIONAL='TRUE';
      INPUT_LOAD='(-0.01,0.01)';
      OUTPUT_LOAD='(1.0,-1.0)';
    'G1':
      PIN_NUMBER='(2)';
      PINUSE='POWER';
      NO_LOAD_CHECK='Both';
      NO_IO_CHECK='Both';
      NO_ASSERT_CHECK='TRUE';
      NO_DIR_CHECK='TRUE';
      ALLOW_CONNECT='TRUE';
    'G2':
      PIN_NUMBER='(4)';
      PINUSE='POWER';
      NO_LOAD_CHECK='Both';
      NO_IO_CHECK='Both';
      NO_ASSERT_CHECK='TRUE';
      NO_DIR_CHECK='TRUE';
      ALLOW_CONNECT='TRUE';
    'X2':
      PIN_NUMBER='(3)';
      BIDIRECTIONAL='TRUE';
      INPUT_LOAD='(-0.01,0.01)';
      OUTPUT_LOAD='(1.0,-1.0)';
  end_pin;
  body
    PART_NAME='Q_XTAL_4P_13BI_24GND';
    BODY_NAME='Q_XTAL_4P_13BI_24GND';
    PHYS_DES_PREFIX='Y';
    CLASS='DISCRETE';
  end_body;
end_primitive;

END.
